(kicad_pcb
	(version 20260206)
	(generator "pcbnew")
	(generator_version "10.0")
	(general
		(thickness 1.6)
		(legacy_teardrops no)
	)
	(paper "A4")
	(title_block
		(title "03242023_DA0F0TMBIJ0_F0T_Motherboard_J_brd_V01_OCP.brd")
		(comment 1 "Grand Teton / footprints 4078-4085 of 6105")
	)
	(layers
		(0 "F.Cu" signal "TOP")
		(4 "In1.Cu" signal "GND")
		(6 "In2.Cu" signal "IN1")
		(8 "In3.Cu" signal "GND1")
		(10 "In4.Cu" signal "IN2")
		(12 "In5.Cu" signal "GND2")
		(14 "In6.Cu" signal "IN3")
		(16 "In7.Cu" signal "GND3")
		(18 "In8.Cu" signal "VCC")
		(20 "In9.Cu" signal "VCC1")
		(22 "In10.Cu" signal "GND4")
		(24 "In11.Cu" signal "IN4")
		(26 "In12.Cu" signal "GND5")
		(28 "In13.Cu" signal "IN5")
		(30 "In14.Cu" signal "GND6")
		(32 "In15.Cu" signal "IN6")
		(34 "In16.Cu" signal "GND7")
		(2 "B.Cu" signal "BOTTOM")
		(9 "F.Adhes" user "F.Adhesive")
		(11 "B.Adhes" user "B.Adhesive")
		(13 "F.Paste" user "Package Geometry/Pastemask Top")
		(15 "B.Paste" user "Package Geometry/Pastemask Bottom")
		(5 "F.SilkS" user "Ref Des/Silkscreen Top")
		(7 "B.SilkS" user "Ref Des/Silkscreen Bottom")
		(1 "F.Mask" user "Board Geometry/Soldermask Top")
		(3 "B.Mask" user "Board Geometry/Soldermask Bottom")
		(17 "Dwgs.User" user "User.Drawings")
		(19 "Cmts.User" user "User.Comments")
		(21 "Eco1.User" user "User.Eco1")
		(23 "Eco2.User" user "User.Eco2")
		(25 "Edge.Cuts" user "Board Geometry/Outline")
		(27 "Margin" user)
		(31 "F.CrtYd" user "Package Geometry/Place Bound Top")
		(29 "B.CrtYd" user "Package Geometry/Place Bound Bottom")
		(35 "F.Fab" user "Ref Des/Assembly Top")
		(33 "B.Fab" user "Ref Des/Assembly Bottom")
	)
	(footprint ""
		(layer "F.Cu")
		(at 369.724178 -355.69779)
		(property "Reference" "R2407"
			(at 0 0 0)
			(layer "F.SilkS")
			(hide yes)
			(effects
				(font
					(size 1.27 1.27)
				)
			)
		)
		(property "Value" ""
			(at 0 0 0)
			(layer "F.Fab")
			(effects
				(font
					(size 1.27 1.27)
				)
			)
		)
		(duplicate_pad_numbers_are_jumpers no)
		(fp_line
			(start -0.7874 -0.4064)
			(end 0.7874 -0.4064)
			(stroke
				(width 0.1524)
				(type default)
			)
			(layer "F.SilkS")
		)
		(fp_line
			(start -0.7874 0.4064)
			(end -0.7874 -0.4064)
			(stroke
				(width 0.1524)
				(type default)
			)
			(layer "F.SilkS")
		)
		(fp_line
			(start 0.7874 -0.4064)
			(end 0.7874 0.4064)
			(stroke
				(width 0.1524)
				(type default)
			)
			(layer "F.SilkS")
		)
		(fp_line
			(start 0.7874 0.4064)
			(end -0.7874 0.4064)
			(stroke
				(width 0.1524)
				(type default)
			)
			(layer "F.SilkS")
		)
		(fp_line
			(start -0.67945 -0.305054)
			(end -0.12065 -0.305054)
			(stroke
				(width 0.1)
				(type default)
			)
			(layer "F.Fab")
		)
		(fp_line
			(start -0.67945 0.3048)
			(end -0.67945 -0.305054)
			(stroke
				(width 0.1)
				(type default)
			)
			(layer "F.Fab")
		)
		(fp_line
			(start -0.12065 -0.305054)
			(end -0.12065 -0.2794)
			(stroke
				(width 0.1)
				(type default)
			)
			(layer "F.Fab")
		)
		(fp_line
			(start -0.12065 -0.2794)
			(end 0.12065 -0.2794)
			(stroke
				(width 0.1)
				(type default)
			)
			(layer "F.Fab")
		)
		(fp_line
			(start -0.12065 0.2794)
			(end -0.12065 0.3048)
			(stroke
				(width 0.1)
				(type default)
			)
			(layer "F.Fab")
		)
		(fp_line
			(start -0.12065 0.3048)
			(end -0.67945 0.3048)
			(stroke
				(width 0.1)
				(type default)
			)
			(layer "F.Fab")
		)
		(fp_line
			(start 0.120396 0.2794)
			(end -0.12065 0.2794)
			(stroke
				(width 0.1)
				(type default)
			)
			(layer "F.Fab")
		)
		(fp_line
			(start 0.120396 0.3048)
			(end 0.120396 0.2794)
			(stroke
				(width 0.1)
				(type default)
			)
			(layer "F.Fab")
		)
		(fp_line
			(start 0.12065 -0.3048)
			(end 0.67945 -0.3048)
			(stroke
				(width 0.1)
				(type default)
			)
			(layer "F.Fab")
		)
		(fp_line
			(start 0.12065 -0.2794)
			(end 0.12065 -0.3048)
			(stroke
				(width 0.1)
				(type default)
			)
			(layer "F.Fab")
		)
		(fp_line
			(start 0.67945 -0.3048)
			(end 0.67945 0.3048)
			(stroke
				(width 0.1)
				(type default)
			)
			(layer "F.Fab")
		)
		(fp_line
			(start 0.67945 0.3048)
			(end 0.120396 0.3048)
			(stroke
				(width 0.1)
				(type default)
			)
			(layer "F.Fab")
		)
		(pad "1" smd circle
			(at -0.40005 0)
			(size 0 0)
			(layers "F.Cu" "F.Mask" "F.Paste")
			(net "P3V3_AUX")
		)
		(pad "2" smd circle
			(at 0.40005 0)
			(size 0 0)
			(layers "F.Cu" "F.Mask" "F.Paste")
			(net "PWRGD_PVPP_HBM_CPU0_R")
		)
	)
	(footprint ""
		(layer "F.Cu")
		(at 54.242716 -107.88269 180)
		(property "Reference" "R3720"
			(at 0 0 180)
			(layer "F.SilkS")
			(hide yes)
			(effects
				(font
					(size 1.27 1.27)
				)
			)
		)
		(property "Value" ""
			(at 0 0 180)
			(layer "F.Fab")
			(effects
				(font
					(size 1.27 1.27)
				)
			)
		)
		(duplicate_pad_numbers_are_jumpers no)
		(fp_line
			(start 0.7874 0.4064)
			(end -0.7874 0.4064)
			(stroke
				(width 0.1524)
				(type default)
			)
			(layer "F.SilkS")
		)
		(fp_line
			(start 0.7874 -0.4064)
			(end 0.7874 0.4064)
			(stroke
				(width 0.1524)
				(type default)
			)
			(layer "F.SilkS")
		)
		(fp_line
			(start -0.7874 0.4064)
			(end -0.7874 -0.4064)
			(stroke
				(width 0.1524)
				(type default)
			)
			(layer "F.SilkS")
		)
		(fp_line
			(start -0.7874 -0.4064)
			(end 0.7874 -0.4064)
			(stroke
				(width 0.1524)
				(type default)
			)
			(layer "F.SilkS")
		)
		(fp_line
			(start 0.67945 0.3048)
			(end 0.120396 0.3048)
			(stroke
				(width 0.1)
				(type default)
			)
			(layer "F.Fab")
		)
		(fp_line
			(start 0.67945 -0.3048)
			(end 0.67945 0.3048)
			(stroke
				(width 0.1)
				(type default)
			)
			(layer "F.Fab")
		)
		(fp_line
			(start 0.12065 -0.2794)
			(end 0.12065 -0.3048)
			(stroke
				(width 0.1)
				(type default)
			)
			(layer "F.Fab")
		)
		(fp_line
			(start 0.12065 -0.3048)
			(end 0.67945 -0.3048)
			(stroke
				(width 0.1)
				(type default)
			)
			(layer "F.Fab")
		)
		(fp_line
			(start 0.120396 0.3048)
			(end 0.120396 0.2794)
			(stroke
				(width 0.1)
				(type default)
			)
			(layer "F.Fab")
		)
		(fp_line
			(start 0.120396 0.2794)
			(end -0.12065 0.2794)
			(stroke
				(width 0.1)
				(type default)
			)
			(layer "F.Fab")
		)
		(fp_line
			(start -0.12065 0.3048)
			(end -0.67945 0.3048)
			(stroke
				(width 0.1)
				(type default)
			)
			(layer "F.Fab")
		)
		(fp_line
			(start -0.12065 0.2794)
			(end -0.12065 0.3048)
			(stroke
				(width 0.1)
				(type default)
			)
			(layer "F.Fab")
		)
		(fp_line
			(start -0.12065 -0.2794)
			(end 0.12065 -0.2794)
			(stroke
				(width 0.1)
				(type default)
			)
			(layer "F.Fab")
		)
		(fp_line
			(start -0.12065 -0.305054)
			(end -0.12065 -0.2794)
			(stroke
				(width 0.1)
				(type default)
			)
			(layer "F.Fab")
		)
		(fp_line
			(start -0.67945 0.3048)
			(end -0.67945 -0.305054)
			(stroke
				(width 0.1)
				(type default)
			)
			(layer "F.Fab")
		)
		(fp_line
			(start -0.67945 -0.305054)
			(end -0.12065 -0.305054)
			(stroke
				(width 0.1)
				(type default)
			)
			(layer "F.Fab")
		)
		(pad "1" smd circle
			(at -0.40005 0 180)
			(size 0 0)
			(layers "F.Cu" "F.Mask" "F.Paste")
			(net "SMB_LM75_2_3V3AUX_SDA_R")
		)
		(pad "2" smd circle
			(at 0.40005 0 180)
			(size 0 0)
			(layers "F.Cu" "F.Mask" "F.Paste")
			(net "SMB_LM75_2_3V3AUX_SDA")
		)
	)
	(footprint ""
		(layer "F.Cu")
		(at 127.602234 -408.517344 -90)
		(property "Reference" "C1520"
			(at 0 0 270)
			(layer "F.SilkS")
			(hide yes)
			(effects
				(font
					(size 1.27 1.27)
				)
			)
		)
		(property "Value" ""
			(at 0 0 270)
			(layer "F.Fab")
			(effects
				(font
					(size 1.27 1.27)
				)
			)
		)
		(duplicate_pad_numbers_are_jumpers no)
		(fp_line
			(start -0.299974 0.150114)
			(end -0.299974 -0.150114)
			(stroke
				(width 0.1)
				(type default)
			)
			(layer "F.Fab")
		)
		(fp_line
			(start 0.299974 0.150114)
			(end -0.299974 0.150114)
			(stroke
				(width 0.1)
				(type default)
			)
			(layer "F.Fab")
		)
		(fp_line
			(start -0.299974 -0.150114)
			(end 0.299974 -0.150114)
			(stroke
				(width 0.1)
				(type default)
			)
			(layer "F.Fab")
		)
		(fp_line
			(start 0.299974 -0.150114)
			(end 0.299974 0.150114)
			(stroke
				(width 0.1)
				(type default)
			)
			(layer "F.Fab")
		)
		(pad "1" smd rect
			(at -0.2667 0 270)
			(size 0.3048 0.381)
			(layers "F.Cu" "F.Mask" "F.Paste")
			(net "P5E_CPU1_PE3_TX_C_DN<13>")
		)
		(pad "2" smd rect
			(at 0.2667 0 270)
			(size 0.3048 0.381)
			(layers "F.Cu" "F.Mask" "F.Paste")
			(net "P5E_CPU1_PE3_TX_DN<13>")
		)
	)
	(footprint ""
		(layer "F.Cu")
		(at 400.558 -183.429148)
		(property "Reference" "PC1579"
			(at 0 0 0)
			(layer "F.SilkS")
			(hide yes)
			(effects
				(font
					(size 1.27 1.27)
				)
			)
		)
		(property "Value" ""
			(at 0 0 0)
			(layer "F.Fab")
			(effects
				(font
					(size 1.27 1.27)
				)
			)
		)
		(duplicate_pad_numbers_are_jumpers no)
		(fp_line
			(start 2.750058 0.999998)
			(end -2.750058 0.999998)
			(stroke
				(width 0.1524)
				(type default)
			)
			(layer "F.SilkS")
		)
		(fp_circle
			(center 0 0.999998)
			(end 2.750058 0.999998)
			(stroke
				(width 0.1524)
				(type default)
			)
			(fill no)
			(layer "F.SilkS")
		)
		(fp_poly
			(pts
				(arc
					(start 2.750058 0.999998)
					(mid 0 3.750056)
					(end -2.750058 0.999998)
				)
			)
			(stroke
				(width 0)
				(type default)
			)
			(fill yes)
			(layer "F.SilkS")
		)
		(fp_circle
			(center 0 0.999998)
			(end 2.750058 0.999998)
			(stroke
				(width 0.1)
				(type default)
			)
			(fill no)
			(layer "F.Fab")
		)
		(pad "1" thru_hole rect
			(at 0 0)
			(size 1.5748 1.5748)
			(drill 1.0668)
			(layers "*.Cu" "*.Mask")
			(remove_unused_layers no)
			(net "PVCCINFAON_CPU0")
			(clearance 0)
			(padstack
				(mode front_inner_back)
				(layer "Inner"
					(shape circle)
					(size 1.5748 1.5748)
					(clearance 0)
				)
				(layer "B.Cu"
					(shape rect)
					(size 1.5748 1.5748)
					(clearance 0)
				)
			)
		)
		(pad "2" thru_hole circle
			(at 0 1.999996)
			(size 1.5748 1.5748)
			(drill 1.0668)
			(layers "*.Cu" "*.Mask")
			(remove_unused_layers no)
			(net "GND")
			(clearance 0)
		)
	)
	(footprint ""
		(layer "F.Cu")
		(at 216.065608 -402.791422 180)
		(property "Reference" "PR3990"
			(at 0 0 180)
			(layer "F.SilkS")
			(hide yes)
			(effects
				(font
					(size 1.27 1.27)
				)
			)
		)
		(property "Value" ""
			(at 0 0 180)
			(layer "F.Fab")
			(effects
				(font
					(size 1.27 1.27)
				)
			)
		)
		(duplicate_pad_numbers_are_jumpers no)
		(fp_line
			(start 0.7874 0.4064)
			(end -0.7874 0.4064)
			(stroke
				(width 0.1524)
				(type default)
			)
			(layer "F.SilkS")
		)
		(fp_line
			(start 0.7874 -0.4064)
			(end 0.7874 0.4064)
			(stroke
				(width 0.1524)
				(type default)
			)
			(layer "F.SilkS")
		)
		(fp_line
			(start -0.7874 0.4064)
			(end -0.7874 -0.4064)
			(stroke
				(width 0.1524)
				(type default)
			)
			(layer "F.SilkS")
		)
		(fp_line
			(start -0.7874 -0.4064)
			(end 0.7874 -0.4064)
			(stroke
				(width 0.1524)
				(type default)
			)
			(layer "F.SilkS")
		)
		(fp_line
			(start 0.67945 0.3048)
			(end 0.120396 0.3048)
			(stroke
				(width 0.1)
				(type default)
			)
			(layer "F.Fab")
		)
		(fp_line
			(start 0.67945 -0.3048)
			(end 0.67945 0.3048)
			(stroke
				(width 0.1)
				(type default)
			)
			(layer "F.Fab")
		)
		(fp_line
			(start 0.12065 -0.2794)
			(end 0.12065 -0.3048)
			(stroke
				(width 0.1)
				(type default)
			)
			(layer "F.Fab")
		)
		(fp_line
			(start 0.12065 -0.3048)
			(end 0.67945 -0.3048)
			(stroke
				(width 0.1)
				(type default)
			)
			(layer "F.Fab")
		)
		(fp_line
			(start 0.120396 0.3048)
			(end 0.120396 0.2794)
			(stroke
				(width 0.1)
				(type default)
			)
			(layer "F.Fab")
		)
		(fp_line
			(start 0.120396 0.2794)
			(end -0.12065 0.2794)
			(stroke
				(width 0.1)
				(type default)
			)
			(layer "F.Fab")
		)
		(fp_line
			(start -0.12065 0.3048)
			(end -0.67945 0.3048)
			(stroke
				(width 0.1)
				(type default)
			)
			(layer "F.Fab")
		)
		(fp_line
			(start -0.12065 0.2794)
			(end -0.12065 0.3048)
			(stroke
				(width 0.1)
				(type default)
			)
			(layer "F.Fab")
		)
		(fp_line
			(start -0.12065 -0.2794)
			(end 0.12065 -0.2794)
			(stroke
				(width 0.1)
				(type default)
			)
			(layer "F.Fab")
		)
		(fp_line
			(start -0.12065 -0.305054)
			(end -0.12065 -0.2794)
			(stroke
				(width 0.1)
				(type default)
			)
			(layer "F.Fab")
		)
		(fp_line
			(start -0.67945 0.3048)
			(end -0.67945 -0.305054)
			(stroke
				(width 0.1)
				(type default)
			)
			(layer "F.Fab")
		)
		(fp_line
			(start -0.67945 -0.305054)
			(end -0.12065 -0.305054)
			(stroke
				(width 0.1)
				(type default)
			)
			(layer "F.Fab")
		)
		(pad "1" smd circle
			(at -0.40005 0 180)
			(size 0 0)
			(layers "F.Cu" "F.Mask" "F.Paste")
			(net "HSC_IMON")
		)
		(pad "2" smd circle
			(at 0.40005 0 180)
			(size 0 0)
			(layers "F.Cu" "F.Mask" "F.Paste")
			(net "AGND_HSC")
		)
	)
	(footprint ""
		(layer "F.Cu")
		(at 353.248214 -252.956314 -90)
		(property "Reference" "C1002"
			(at 0 0 270)
			(layer "F.SilkS")
			(hide yes)
			(effects
				(font
					(size 1.27 1.27)
				)
			)
		)
		(property "Value" ""
			(at 0 0 270)
			(layer "F.Fab")
			(effects
				(font
					(size 1.27 1.27)
				)
			)
		)
		(duplicate_pad_numbers_are_jumpers no)
		(fp_line
			(start -0.7874 0.4064)
			(end -0.7874 -0.4064)
			(stroke
				(width 0.1524)
				(type default)
			)
			(layer "F.SilkS")
		)
		(fp_line
			(start 0.7874 0.4064)
			(end -0.7874 0.4064)
			(stroke
				(width 0.1524)
				(type default)
			)
			(layer "F.SilkS")
		)
		(fp_line
			(start -0.7874 -0.4064)
			(end 0.7874 -0.4064)
			(stroke
				(width 0.1524)
				(type default)
			)
			(layer "F.SilkS")
		)
		(fp_line
			(start 0.7874 -0.4064)
			(end 0.7874 0.4064)
			(stroke
				(width 0.1524)
				(type default)
			)
			(layer "F.SilkS")
		)
		(fp_line
			(start -0.67945 0.3048)
			(end -0.67945 -0.305054)
			(stroke
				(width 0.1)
				(type default)
			)
			(layer "F.Fab")
		)
		(fp_line
			(start -0.12065 0.3048)
			(end -0.67945 0.3048)
			(stroke
				(width 0.1)
				(type default)
			)
			(layer "F.Fab")
		)
		(fp_line
			(start 0.120396 0.3048)
			(end 0.120396 0.2794)
			(stroke
				(width 0.1)
				(type default)
			)
			(layer "F.Fab")
		)
		(fp_line
			(start 0.67945 0.3048)
			(end 0.120396 0.3048)
			(stroke
				(width 0.1)
				(type default)
			)
			(layer "F.Fab")
		)
		(fp_line
			(start -0.12065 0.2794)
			(end -0.12065 0.3048)
			(stroke
				(width 0.1)
				(type default)
			)
			(layer "F.Fab")
		)
		(fp_line
			(start 0.120396 0.2794)
			(end -0.12065 0.2794)
			(stroke
				(width 0.1)
				(type default)
			)
			(layer "F.Fab")
		)
		(fp_line
			(start -0.12065 -0.2794)
			(end 0.12065 -0.2794)
			(stroke
				(width 0.1)
				(type default)
			)
			(layer "F.Fab")
		)
		(fp_line
			(start 0.12065 -0.2794)
			(end 0.12065 -0.3048)
			(stroke
				(width 0.1)
				(type default)
			)
			(layer "F.Fab")
		)
		(fp_line
			(start 0.12065 -0.3048)
			(end 0.67945 -0.3048)
			(stroke
				(width 0.1)
				(type default)
			)
			(layer "F.Fab")
		)
		(fp_line
			(start 0.67945 -0.3048)
			(end 0.67945 0.3048)
			(stroke
				(width 0.1)
				(type default)
			)
			(layer "F.Fab")
		)
		(fp_line
			(start -0.67945 -0.305054)
			(end -0.12065 -0.305054)
			(stroke
				(width 0.1)
				(type default)
			)
			(layer "F.Fab")
		)
		(fp_line
			(start -0.12065 -0.305054)
			(end -0.12065 -0.2794)
			(stroke
				(width 0.1)
				(type default)
			)
			(layer "F.Fab")
		)
		(pad "1" smd circle
			(at -0.40005 0 270)
			(size 0 0)
			(layers "F.Cu" "F.Mask" "F.Paste")
			(net "PVCCIN_CPU0")
		)
		(pad "2" smd circle
			(at 0.40005 0 270)
			(size 0 0)
			(layers "F.Cu" "F.Mask" "F.Paste")
			(net "GND")
		)
	)
	(footprint ""
		(layer "F.Cu")
		(at 403.941026 -64.040004)
		(property "Reference" "C549"
			(at 0 0 0)
			(layer "F.SilkS")
			(hide yes)
			(effects
				(font
					(size 1.27 1.27)
				)
			)
		)
		(property "Value" ""
			(at 0 0 0)
			(layer "F.Fab")
			(effects
				(font
					(size 1.27 1.27)
				)
			)
		)
		(duplicate_pad_numbers_are_jumpers no)
		(fp_line
			(start -0.7874 -0.4064)
			(end 0.7874 -0.4064)
			(stroke
				(width 0.1524)
				(type default)
			)
			(layer "F.SilkS")
		)
		(fp_line
			(start -0.7874 0.4064)
			(end -0.7874 -0.4064)
			(stroke
				(width 0.1524)
				(type default)
			)
			(layer "F.SilkS")
		)
		(fp_line
			(start 0.7874 -0.4064)
			(end 0.7874 0.4064)
			(stroke
				(width 0.1524)
				(type default)
			)
			(layer "F.SilkS")
		)
		(fp_line
			(start 0.7874 0.4064)
			(end -0.7874 0.4064)
			(stroke
				(width 0.1524)
				(type default)
			)
			(layer "F.SilkS")
		)
		(fp_line
			(start -0.67945 -0.305054)
			(end -0.12065 -0.305054)
			(stroke
				(width 0.1)
				(type default)
			)
			(layer "F.Fab")
		)
		(fp_line
			(start -0.67945 0.3048)
			(end -0.67945 -0.305054)
			(stroke
				(width 0.1)
				(type default)
			)
			(layer "F.Fab")
		)
		(fp_line
			(start -0.12065 -0.305054)
			(end -0.12065 -0.2794)
			(stroke
				(width 0.1)
				(type default)
			)
			(layer "F.Fab")
		)
		(fp_line
			(start -0.12065 -0.2794)
			(end 0.12065 -0.2794)
			(stroke
				(width 0.1)
				(type default)
			)
			(layer "F.Fab")
		)
		(fp_line
			(start -0.12065 0.2794)
			(end -0.12065 0.3048)
			(stroke
				(width 0.1)
				(type default)
			)
			(layer "F.Fab")
		)
		(fp_line
			(start -0.12065 0.3048)
			(end -0.67945 0.3048)
			(stroke
				(width 0.1)
				(type default)
			)
			(layer "F.Fab")
		)
		(fp_line
			(start 0.120396 0.2794)
			(end -0.12065 0.2794)
			(stroke
				(width 0.1)
				(type default)
			)
			(layer "F.Fab")
		)
		(fp_line
			(start 0.120396 0.3048)
			(end 0.120396 0.2794)
			(stroke
				(width 0.1)
				(type default)
			)
			(layer "F.Fab")
		)
		(fp_line
			(start 0.12065 -0.3048)
			(end 0.67945 -0.3048)
			(stroke
				(width 0.1)
				(type default)
			)
			(layer "F.Fab")
		)
		(fp_line
			(start 0.12065 -0.2794)
			(end 0.12065 -0.3048)
			(stroke
				(width 0.1)
				(type default)
			)
			(layer "F.Fab")
		)
		(fp_line
			(start 0.67945 -0.3048)
			(end 0.67945 0.3048)
			(stroke
				(width 0.1)
				(type default)
			)
			(layer "F.Fab")
		)
		(fp_line
			(start 0.67945 0.3048)
			(end 0.120396 0.3048)
			(stroke
				(width 0.1)
				(type default)
			)
			(layer "F.Fab")
		)
		(pad "1" smd circle
			(at -0.40005 0)
			(size 0 0)
			(layers "F.Cu" "F.Mask" "F.Paste")
			(net "JTAG_RST_DBP_RST_CO_N")
		)
		(pad "2" smd circle
			(at 0.40005 0)
			(size 0 0)
			(layers "F.Cu" "F.Mask" "F.Paste")
			(net "GND")
		)
	)
	(footprint ""
		(layer "F.Cu")
		(at 484.125016 -470.302844)
		(property "Reference" "J90_CON"
			(at -3.668776 -2.231644 0)
			(unlocked yes)
			(layer "F.SilkS")
			(effects
				(font
					(size 0.7874 0.5842)
					(thickness 0.1524)
				)
				(justify left)
			)
		)
		(property "Value" ""
			(at 0 0 0)
			(layer "F.Fab")
			(effects
				(font
					(size 1.27 1.27)
				)
			)
		)
		(duplicate_pad_numbers_are_jumpers no)
		(pad "1" smd circle
			(at 0 0)
			(size 0.762 0.762)
			(layers "F.Cu" "F.Mask" "F.Paste")
			(net "Net_8608")
		)
	)
)
